FILE_TYPE = MULTI_PHYS_TABLE;

PART 'SHT31A_DIS_B10KS_DFN8'
CLASS = IC

{========================================================================================}
: CLS_PN         | VALUE                 =  JEDEC_TYPE                 | ALT_SYMBOLS                  | DESCRIPTION                                              | CPN_STATUS;
{========================================================================================}
 'A222-00001-FB' | 'SHT31A-DIS-B10KS'    = 'DFN9_098_P0197_TR039X071'  |'(DFN9_098_P0197_TR039X071)'  |'IC,SHT31A-DIS,HUMIDITY AND TEMPERATURE SENSOR,SMT,DFN-8' |''

END_PART

END.

